(kicad_pcb
	(version 20260206)
	(generator "pcbnew")
	(generator_version "10.0")
	(general
		(thickness 1.6)
		(legacy_teardrops no)
	)
	(paper "A4")
	(title_block
		(title "04192023_DAF0TMB3IC0_F0TG_MB_C_brd_V02_OCP.brd")
		(comment 1 "Grand Teton / footprints 4831-4837 of 8354")
	)
	(layers
		(0 "F.Cu" signal "TOP")
		(4 "In1.Cu" signal "GND")
		(6 "In2.Cu" signal "IN1")
		(8 "In3.Cu" signal "GND1")
		(10 "In4.Cu" signal "IN2")
		(12 "In5.Cu" signal "GND2")
		(14 "In6.Cu" signal "IN3")
		(16 "In7.Cu" signal "GND3")
		(18 "In8.Cu" signal "VCC")
		(20 "In9.Cu" signal "VCC1")
		(22 "In10.Cu" signal "GND4")
		(24 "In11.Cu" signal "IN4")
		(26 "In12.Cu" signal "GND5")
		(28 "In13.Cu" signal "IN5")
		(30 "In14.Cu" signal "GND6")
		(32 "In15.Cu" signal "IN6")
		(34 "In16.Cu" signal "GND7")
		(2 "B.Cu" signal "BOTTOM")
		(9 "F.Adhes" user "F.Adhesive")
		(11 "B.Adhes" user "B.Adhesive")
		(13 "F.Paste" user "Package Geometry/Pastemask Top")
		(15 "B.Paste" user "Package Geometry/Pastemask Bottom")
		(5 "F.SilkS" user "Ref Des/Silkscreen Top")
		(7 "B.SilkS" user "Ref Des/Silkscreen Bottom")
		(1 "F.Mask" user "Board Geometry/Soldermask Top")
		(3 "B.Mask" user "Board Geometry/Soldermask Bottom")
		(17 "Dwgs.User" user "User.Drawings")
		(19 "Cmts.User" user "User.Comments")
		(21 "Eco1.User" user "User.Eco1")
		(23 "Eco2.User" user "User.Eco2")
		(25 "Edge.Cuts" user "Board Geometry/Outline")
		(27 "Margin" user)
		(31 "F.CrtYd" user "Package Geometry/Place Bound Top")
		(29 "B.CrtYd" user "Package Geometry/Place Bound Bottom")
		(35 "F.Fab" user "Ref Des/Assembly Top")
		(33 "B.Fab" user "Ref Des/Assembly Bottom")
	)
	(footprint ""
		(layer "F.Cu")
		(at 171.196 -118.328948)
		(property "Reference" "R211"
			(at 0 0 0)
			(layer "F.SilkS")
			(hide yes)
			(effects
				(font
					(size 1.27 1.27)
				)
			)
		)
		(property "Value" ""
			(at 0 0 0)
			(layer "F.Fab")
			(effects
				(font
					(size 1.27 1.27)
				)
			)
		)
		(duplicate_pad_numbers_are_jumpers no)
		(fp_line
			(start -0.7874 -0.4064)
			(end 0.7874 -0.4064)
			(stroke
				(width 0.1524)
				(type default)
			)
			(layer "F.SilkS")
		)
		(fp_line
			(start -0.7874 0.4064)
			(end -0.7874 -0.4064)
			(stroke
				(width 0.1524)
				(type default)
			)
			(layer "F.SilkS")
		)
		(fp_line
			(start 0.7874 -0.4064)
			(end 0.7874 0.4064)
			(stroke
				(width 0.1524)
				(type default)
			)
			(layer "F.SilkS")
		)
		(fp_line
			(start 0.7874 0.4064)
			(end -0.7874 0.4064)
			(stroke
				(width 0.1524)
				(type default)
			)
			(layer "F.SilkS")
		)
		(fp_line
			(start -0.67945 -0.305054)
			(end -0.12065 -0.305054)
			(stroke
				(width 0.1)
				(type default)
			)
			(layer "F.Fab")
		)
		(fp_line
			(start -0.67945 0.3048)
			(end -0.67945 -0.305054)
			(stroke
				(width 0.1)
				(type default)
			)
			(layer "F.Fab")
		)
		(fp_line
			(start -0.12065 -0.305054)
			(end -0.12065 -0.2794)
			(stroke
				(width 0.1)
				(type default)
			)
			(layer "F.Fab")
		)
		(fp_line
			(start -0.12065 -0.2794)
			(end 0.12065 -0.2794)
			(stroke
				(width 0.1)
				(type default)
			)
			(layer "F.Fab")
		)
		(fp_line
			(start -0.12065 0.2794)
			(end -0.12065 0.3048)
			(stroke
				(width 0.1)
				(type default)
			)
			(layer "F.Fab")
		)
		(fp_line
			(start -0.12065 0.3048)
			(end -0.67945 0.3048)
			(stroke
				(width 0.1)
				(type default)
			)
			(layer "F.Fab")
		)
		(fp_line
			(start 0.120396 0.2794)
			(end -0.12065 0.2794)
			(stroke
				(width 0.1)
				(type default)
			)
			(layer "F.Fab")
		)
		(fp_line
			(start 0.120396 0.3048)
			(end 0.120396 0.2794)
			(stroke
				(width 0.1)
				(type default)
			)
			(layer "F.Fab")
		)
		(fp_line
			(start 0.12065 -0.3048)
			(end 0.67945 -0.3048)
			(stroke
				(width 0.1)
				(type default)
			)
			(layer "F.Fab")
		)
		(fp_line
			(start 0.12065 -0.2794)
			(end 0.12065 -0.3048)
			(stroke
				(width 0.1)
				(type default)
			)
			(layer "F.Fab")
		)
		(fp_line
			(start 0.67945 -0.3048)
			(end 0.67945 0.3048)
			(stroke
				(width 0.1)
				(type default)
			)
			(layer "F.Fab")
		)
		(fp_line
			(start 0.67945 0.3048)
			(end 0.120396 0.3048)
			(stroke
				(width 0.1)
				(type default)
			)
			(layer "F.Fab")
		)
		(pad "1" smd circle
			(at -0.40005 0)
			(size 0 0)
			(layers "F.Cu" "F.Mask" "F.Paste")
			(net "SMB_2_PLD_3V3AUX_SDA_R1")
		)
		(pad "2" smd circle
			(at 0.40005 0)
			(size 0 0)
			(layers "F.Cu" "F.Mask" "F.Paste")
			(net "SMB_2_PLD_3V3AUX_SDA_R2")
		)
	)
	(footprint ""
		(layer "F.Cu")
		(at 428.287688 -353.80549 90)
		(property "Reference" "PC204"
			(at 0 0 90)
			(layer "F.SilkS")
			(hide yes)
			(effects
				(font
					(size 1.27 1.27)
				)
			)
		)
		(property "Value" ""
			(at 0 0 90)
			(layer "F.Fab")
			(effects
				(font
					(size 1.27 1.27)
				)
			)
		)
		(duplicate_pad_numbers_are_jumpers no)
		(fp_line
			(start 0.7874 -0.4064)
			(end 0.7874 0.4064)
			(stroke
				(width 0.1524)
				(type default)
			)
			(layer "F.SilkS")
		)
		(fp_line
			(start -0.7874 -0.4064)
			(end 0.7874 -0.4064)
			(stroke
				(width 0.1524)
				(type default)
			)
			(layer "F.SilkS")
		)
		(fp_line
			(start 0.7874 0.4064)
			(end 0.44831 0.4064)
			(stroke
				(width 0.1524)
				(type default)
			)
			(layer "F.SilkS")
		)
		(fp_line
			(start -0.23749 0.4064)
			(end -0.7874 0.4064)
			(stroke
				(width 0.1524)
				(type default)
			)
			(layer "F.SilkS")
		)
		(fp_line
			(start -0.7874 0.4064)
			(end -0.7874 -0.4064)
			(stroke
				(width 0.1524)
				(type default)
			)
			(layer "F.SilkS")
		)
		(fp_line
			(start -0.12065 -0.305054)
			(end -0.12065 -0.2794)
			(stroke
				(width 0.1)
				(type default)
			)
			(layer "F.Fab")
		)
		(fp_line
			(start -0.67945 -0.305054)
			(end -0.12065 -0.305054)
			(stroke
				(width 0.1)
				(type default)
			)
			(layer "F.Fab")
		)
		(fp_line
			(start 0.67945 -0.3048)
			(end 0.67945 0.3048)
			(stroke
				(width 0.1)
				(type default)
			)
			(layer "F.Fab")
		)
		(fp_line
			(start 0.12065 -0.3048)
			(end 0.67945 -0.3048)
			(stroke
				(width 0.1)
				(type default)
			)
			(layer "F.Fab")
		)
		(fp_line
			(start 0.12065 -0.2794)
			(end 0.12065 -0.3048)
			(stroke
				(width 0.1)
				(type default)
			)
			(layer "F.Fab")
		)
		(fp_line
			(start -0.12065 -0.2794)
			(end 0.12065 -0.2794)
			(stroke
				(width 0.1)
				(type default)
			)
			(layer "F.Fab")
		)
		(fp_line
			(start 0.120396 0.2794)
			(end -0.12065 0.2794)
			(stroke
				(width 0.1)
				(type default)
			)
			(layer "F.Fab")
		)
		(fp_line
			(start -0.12065 0.2794)
			(end -0.12065 0.3048)
			(stroke
				(width 0.1)
				(type default)
			)
			(layer "F.Fab")
		)
		(fp_line
			(start 0.67945 0.3048)
			(end 0.120396 0.3048)
			(stroke
				(width 0.1)
				(type default)
			)
			(layer "F.Fab")
		)
		(fp_line
			(start 0.120396 0.3048)
			(end 0.120396 0.2794)
			(stroke
				(width 0.1)
				(type default)
			)
			(layer "F.Fab")
		)
		(fp_line
			(start -0.12065 0.3048)
			(end -0.67945 0.3048)
			(stroke
				(width 0.1)
				(type default)
			)
			(layer "F.Fab")
		)
		(fp_line
			(start -0.67945 0.3048)
			(end -0.67945 -0.305054)
			(stroke
				(width 0.1)
				(type default)
			)
			(layer "F.Fab")
		)
		(pad "1" smd circle
			(at -0.40005 0 90)
			(size 0 0)
			(layers "F.Cu" "F.Mask" "F.Paste")
			(net "PVDD11_S3_P0_VCC2")
		)
		(pad "2" smd circle
			(at 0.40005 0 90)
			(size 0 0)
			(layers "F.Cu" "F.Mask" "F.Paste")
			(net "GND")
		)
	)
	(footprint ""
		(layer "F.Cu")
		(at 307.404516 -437.498744 90)
		(property "Reference" "R4133"
			(at 0 0 90)
			(layer "F.SilkS")
			(hide yes)
			(effects
				(font
					(size 1.27 1.27)
				)
			)
		)
		(property "Value" ""
			(at 0 0 90)
			(layer "F.Fab")
			(effects
				(font
					(size 1.27 1.27)
				)
			)
		)
		(duplicate_pad_numbers_are_jumpers no)
		(fp_line
			(start 0.7874 -0.4064)
			(end 0.7874 0.4064)
			(stroke
				(width 0.1524)
				(type default)
			)
			(layer "F.SilkS")
		)
		(fp_line
			(start -0.7874 -0.4064)
			(end 0.7874 -0.4064)
			(stroke
				(width 0.1524)
				(type default)
			)
			(layer "F.SilkS")
		)
		(fp_line
			(start 0.7874 0.4064)
			(end -0.7874 0.4064)
			(stroke
				(width 0.1524)
				(type default)
			)
			(layer "F.SilkS")
		)
		(fp_line
			(start -0.7874 0.4064)
			(end -0.7874 -0.4064)
			(stroke
				(width 0.1524)
				(type default)
			)
			(layer "F.SilkS")
		)
		(fp_line
			(start -0.12065 -0.305054)
			(end -0.12065 -0.2794)
			(stroke
				(width 0.1)
				(type default)
			)
			(layer "F.Fab")
		)
		(fp_line
			(start -0.67945 -0.305054)
			(end -0.12065 -0.305054)
			(stroke
				(width 0.1)
				(type default)
			)
			(layer "F.Fab")
		)
		(fp_line
			(start 0.67945 -0.3048)
			(end 0.67945 0.3048)
			(stroke
				(width 0.1)
				(type default)
			)
			(layer "F.Fab")
		)
		(fp_line
			(start 0.12065 -0.3048)
			(end 0.67945 -0.3048)
			(stroke
				(width 0.1)
				(type default)
			)
			(layer "F.Fab")
		)
		(fp_line
			(start 0.12065 -0.2794)
			(end 0.12065 -0.3048)
			(stroke
				(width 0.1)
				(type default)
			)
			(layer "F.Fab")
		)
		(fp_line
			(start -0.12065 -0.2794)
			(end 0.12065 -0.2794)
			(stroke
				(width 0.1)
				(type default)
			)
			(layer "F.Fab")
		)
		(fp_line
			(start 0.120396 0.2794)
			(end -0.12065 0.2794)
			(stroke
				(width 0.1)
				(type default)
			)
			(layer "F.Fab")
		)
		(fp_line
			(start -0.12065 0.2794)
			(end -0.12065 0.3048)
			(stroke
				(width 0.1)
				(type default)
			)
			(layer "F.Fab")
		)
		(fp_line
			(start 0.67945 0.3048)
			(end 0.120396 0.3048)
			(stroke
				(width 0.1)
				(type default)
			)
			(layer "F.Fab")
		)
		(fp_line
			(start 0.120396 0.3048)
			(end 0.120396 0.2794)
			(stroke
				(width 0.1)
				(type default)
			)
			(layer "F.Fab")
		)
		(fp_line
			(start -0.12065 0.3048)
			(end -0.67945 0.3048)
			(stroke
				(width 0.1)
				(type default)
			)
			(layer "F.Fab")
		)
		(fp_line
			(start -0.67945 0.3048)
			(end -0.67945 -0.305054)
			(stroke
				(width 0.1)
				(type default)
			)
			(layer "F.Fab")
		)
		(pad "1" smd circle
			(at -0.40005 0 90)
			(size 0 0)
			(layers "F.Cu" "F.Mask" "F.Paste")
			(net "P3V3_AUX")
		)
		(pad "2" smd circle
			(at 0.40005 0 90)
			(size 0 0)
			(layers "F.Cu" "F.Mask" "F.Paste")
			(net "GPU_3V3IO_RSVD5_FFU")
		)
	)
	(footprint ""
		(layer "F.Cu")
		(at 108.760514 -172.960284)
		(property "Reference" "PR196"
			(at 0 0 0)
			(layer "F.SilkS")
			(hide yes)
			(effects
				(font
					(size 1.27 1.27)
				)
			)
		)
		(property "Value" ""
			(at 0 0 0)
			(layer "F.Fab")
			(effects
				(font
					(size 1.27 1.27)
				)
			)
		)
		(duplicate_pad_numbers_are_jumpers no)
		(fp_line
			(start -0.7874 -0.4064)
			(end 0.7874 -0.4064)
			(stroke
				(width 0.1524)
				(type default)
			)
			(layer "F.SilkS")
		)
		(fp_line
			(start -0.7874 0.4064)
			(end -0.7874 -0.4064)
			(stroke
				(width 0.1524)
				(type default)
			)
			(layer "F.SilkS")
		)
		(fp_line
			(start 0.7874 -0.4064)
			(end 0.7874 0.4064)
			(stroke
				(width 0.1524)
				(type default)
			)
			(layer "F.SilkS")
		)
		(fp_line
			(start 0.7874 0.4064)
			(end -0.7874 0.4064)
			(stroke
				(width 0.1524)
				(type default)
			)
			(layer "F.SilkS")
		)
		(fp_line
			(start -0.67945 -0.305054)
			(end -0.12065 -0.305054)
			(stroke
				(width 0.1)
				(type default)
			)
			(layer "F.Fab")
		)
		(fp_line
			(start -0.67945 0.3048)
			(end -0.67945 -0.305054)
			(stroke
				(width 0.1)
				(type default)
			)
			(layer "F.Fab")
		)
		(fp_line
			(start -0.12065 -0.305054)
			(end -0.12065 -0.2794)
			(stroke
				(width 0.1)
				(type default)
			)
			(layer "F.Fab")
		)
		(fp_line
			(start -0.12065 -0.2794)
			(end 0.12065 -0.2794)
			(stroke
				(width 0.1)
				(type default)
			)
			(layer "F.Fab")
		)
		(fp_line
			(start -0.12065 0.2794)
			(end -0.12065 0.3048)
			(stroke
				(width 0.1)
				(type default)
			)
			(layer "F.Fab")
		)
		(fp_line
			(start -0.12065 0.3048)
			(end -0.67945 0.3048)
			(stroke
				(width 0.1)
				(type default)
			)
			(layer "F.Fab")
		)
		(fp_line
			(start 0.120396 0.2794)
			(end -0.12065 0.2794)
			(stroke
				(width 0.1)
				(type default)
			)
			(layer "F.Fab")
		)
		(fp_line
			(start 0.120396 0.3048)
			(end 0.120396 0.2794)
			(stroke
				(width 0.1)
				(type default)
			)
			(layer "F.Fab")
		)
		(fp_line
			(start 0.12065 -0.3048)
			(end 0.67945 -0.3048)
			(stroke
				(width 0.1)
				(type default)
			)
			(layer "F.Fab")
		)
		(fp_line
			(start 0.12065 -0.2794)
			(end 0.12065 -0.3048)
			(stroke
				(width 0.1)
				(type default)
			)
			(layer "F.Fab")
		)
		(fp_line
			(start 0.67945 -0.3048)
			(end 0.67945 0.3048)
			(stroke
				(width 0.1)
				(type default)
			)
			(layer "F.Fab")
		)
		(fp_line
			(start 0.67945 0.3048)
			(end 0.120396 0.3048)
			(stroke
				(width 0.1)
				(type default)
			)
			(layer "F.Fab")
		)
		(pad "1" smd circle
			(at -0.40005 0)
			(size 0 0)
			(layers "F.Cu" "F.Mask" "F.Paste")
			(net "GND")
		)
		(pad "2" smd circle
			(at 0.40005 0)
			(size 0 0)
			(layers "F.Cu" "F.Mask" "F.Paste")
			(net "PVDDCR_CPU0_P1_LSET4")
		)
	)
	(footprint ""
		(layer "F.Cu")
		(at 328.274426 -416.899344 -90)
		(property "Reference" "C6518"
			(at 0 0 270)
			(layer "F.SilkS")
			(hide yes)
			(effects
				(font
					(size 1.27 1.27)
				)
			)
		)
		(property "Value" ""
			(at 0 0 270)
			(layer "F.Fab")
			(effects
				(font
					(size 1.27 1.27)
				)
			)
		)
		(duplicate_pad_numbers_are_jumpers no)
		(fp_line
			(start -0.299974 0.150114)
			(end -0.299974 -0.150114)
			(stroke
				(width 0.1)
				(type default)
			)
			(layer "F.Fab")
		)
		(fp_line
			(start 0.299974 0.150114)
			(end -0.299974 0.150114)
			(stroke
				(width 0.1)
				(type default)
			)
			(layer "F.Fab")
		)
		(fp_line
			(start -0.299974 -0.150114)
			(end 0.299974 -0.150114)
			(stroke
				(width 0.1)
				(type default)
			)
			(layer "F.Fab")
		)
		(fp_line
			(start 0.299974 -0.150114)
			(end 0.299974 0.150114)
			(stroke
				(width 0.1)
				(type default)
			)
			(layer "F.Fab")
		)
		(pad "1" smd rect
			(at -0.2667 0 270)
			(size 0.3048 0.381)
			(layers "F.Cu" "F.Mask" "F.Paste")
			(net "P5E_CPU0_P0_TX_BUF_C_DN<8>")
		)
		(pad "2" smd rect
			(at 0.2667 0 270)
			(size 0.3048 0.381)
			(layers "F.Cu" "F.Mask" "F.Paste")
			(net "P5E_CPU0_P0_TX_BUF_DN<8>")
		)
	)
	(footprint ""
		(layer "F.Cu")
		(at 279.570942 -380.66853)
		(property "Reference" "PR2538"
			(at 0 0 0)
			(layer "F.SilkS")
			(hide yes)
			(effects
				(font
					(size 1.27 1.27)
				)
			)
		)
		(property "Value" ""
			(at 0 0 0)
			(layer "F.Fab")
			(effects
				(font
					(size 1.27 1.27)
				)
			)
		)
		(duplicate_pad_numbers_are_jumpers no)
		(fp_line
			(start -0.7874 -0.4064)
			(end 0.7874 -0.4064)
			(stroke
				(width 0.1524)
				(type default)
			)
			(layer "F.SilkS")
		)
		(fp_line
			(start -0.7874 0.4064)
			(end -0.7874 -0.4064)
			(stroke
				(width 0.1524)
				(type default)
			)
			(layer "F.SilkS")
		)
		(fp_line
			(start 0.7874 -0.4064)
			(end 0.7874 0.4064)
			(stroke
				(width 0.1524)
				(type default)
			)
			(layer "F.SilkS")
		)
		(fp_line
			(start 0.7874 0.4064)
			(end -0.7874 0.4064)
			(stroke
				(width 0.1524)
				(type default)
			)
			(layer "F.SilkS")
		)
		(fp_line
			(start -0.67945 -0.305054)
			(end -0.12065 -0.305054)
			(stroke
				(width 0.1)
				(type default)
			)
			(layer "F.Fab")
		)
		(fp_line
			(start -0.67945 0.3048)
			(end -0.67945 -0.305054)
			(stroke
				(width 0.1)
				(type default)
			)
			(layer "F.Fab")
		)
		(fp_line
			(start -0.12065 -0.305054)
			(end -0.12065 -0.2794)
			(stroke
				(width 0.1)
				(type default)
			)
			(layer "F.Fab")
		)
		(fp_line
			(start -0.12065 -0.2794)
			(end 0.12065 -0.2794)
			(stroke
				(width 0.1)
				(type default)
			)
			(layer "F.Fab")
		)
		(fp_line
			(start -0.12065 0.2794)
			(end -0.12065 0.3048)
			(stroke
				(width 0.1)
				(type default)
			)
			(layer "F.Fab")
		)
		(fp_line
			(start -0.12065 0.3048)
			(end -0.67945 0.3048)
			(stroke
				(width 0.1)
				(type default)
			)
			(layer "F.Fab")
		)
		(fp_line
			(start 0.120396 0.2794)
			(end -0.12065 0.2794)
			(stroke
				(width 0.1)
				(type default)
			)
			(layer "F.Fab")
		)
		(fp_line
			(start 0.120396 0.3048)
			(end 0.120396 0.2794)
			(stroke
				(width 0.1)
				(type default)
			)
			(layer "F.Fab")
		)
		(fp_line
			(start 0.12065 -0.3048)
			(end 0.67945 -0.3048)
			(stroke
				(width 0.1)
				(type default)
			)
			(layer "F.Fab")
		)
		(fp_line
			(start 0.12065 -0.2794)
			(end 0.12065 -0.3048)
			(stroke
				(width 0.1)
				(type default)
			)
			(layer "F.Fab")
		)
		(fp_line
			(start 0.67945 -0.3048)
			(end 0.67945 0.3048)
			(stroke
				(width 0.1)
				(type default)
			)
			(layer "F.Fab")
		)
		(fp_line
			(start 0.67945 0.3048)
			(end 0.120396 0.3048)
			(stroke
				(width 0.1)
				(type default)
			)
			(layer "F.Fab")
		)
		(pad "1" smd circle
			(at -0.40005 0)
			(size 0 0)
			(layers "F.Cu" "F.Mask" "F.Paste")
			(net "MB0_CM_GATE_G0")
		)
		(pad "2" smd circle
			(at 0.40005 0)
			(size 0 0)
			(layers "F.Cu" "F.Mask" "F.Paste")
			(net "P12V_HSC_GATE1")
		)
	)
	(footprint ""
		(layer "F.Cu")
		(at 252.08484 -92.719144 -90)
		(property "Reference" "R1640"
			(at 0 0 270)
			(layer "F.SilkS")
			(hide yes)
			(effects
				(font
					(size 1.27 1.27)
				)
			)
		)
		(property "Value" ""
			(at 0 0 270)
			(layer "F.Fab")
			(effects
				(font
					(size 1.27 1.27)
				)
			)
		)
		(duplicate_pad_numbers_are_jumpers no)
		(fp_line
			(start -0.7874 0.4064)
			(end -0.7874 -0.4064)
			(stroke
				(width 0.1524)
				(type default)
			)
			(layer "F.SilkS")
		)
		(fp_line
			(start 0.7874 0.4064)
			(end -0.7874 0.4064)
			(stroke
				(width 0.1524)
				(type default)
			)
			(layer "F.SilkS")
		)
		(fp_line
			(start -0.7874 -0.4064)
			(end 0.7874 -0.4064)
			(stroke
				(width 0.1524)
				(type default)
			)
			(layer "F.SilkS")
		)
		(fp_line
			(start 0.7874 -0.4064)
			(end 0.7874 0.4064)
			(stroke
				(width 0.1524)
				(type default)
			)
			(layer "F.SilkS")
		)
		(fp_line
			(start -0.67945 0.3048)
			(end -0.67945 -0.305054)
			(stroke
				(width 0.1)
				(type default)
			)
			(layer "F.Fab")
		)
		(fp_line
			(start -0.12065 0.3048)
			(end -0.67945 0.3048)
			(stroke
				(width 0.1)
				(type default)
			)
			(layer "F.Fab")
		)
		(fp_line
			(start 0.120396 0.3048)
			(end 0.120396 0.2794)
			(stroke
				(width 0.1)
				(type default)
			)
			(layer "F.Fab")
		)
		(fp_line
			(start 0.67945 0.3048)
			(end 0.120396 0.3048)
			(stroke
				(width 0.1)
				(type default)
			)
			(layer "F.Fab")
		)
		(fp_line
			(start -0.12065 0.2794)
			(end -0.12065 0.3048)
			(stroke
				(width 0.1)
				(type default)
			)
			(layer "F.Fab")
		)
		(fp_line
			(start 0.120396 0.2794)
			(end -0.12065 0.2794)
			(stroke
				(width 0.1)
				(type default)
			)
			(layer "F.Fab")
		)
		(fp_line
			(start -0.12065 -0.2794)
			(end 0.12065 -0.2794)
			(stroke
				(width 0.1)
				(type default)
			)
			(layer "F.Fab")
		)
		(fp_line
			(start 0.12065 -0.2794)
			(end 0.12065 -0.3048)
			(stroke
				(width 0.1)
				(type default)
			)
			(layer "F.Fab")
		)
		(fp_line
			(start 0.12065 -0.3048)
			(end 0.67945 -0.3048)
			(stroke
				(width 0.1)
				(type default)
			)
			(layer "F.Fab")
		)
		(fp_line
			(start 0.67945 -0.3048)
			(end 0.67945 0.3048)
			(stroke
				(width 0.1)
				(type default)
			)
			(layer "F.Fab")
		)
		(fp_line
			(start -0.67945 -0.305054)
			(end -0.12065 -0.305054)
			(stroke
				(width 0.1)
				(type default)
			)
			(layer "F.Fab")
		)
		(fp_line
			(start -0.12065 -0.305054)
			(end -0.12065 -0.2794)
			(stroke
				(width 0.1)
				(type default)
			)
			(layer "F.Fab")
		)
		(pad "1" smd circle
			(at -0.40005 0 270)
			(size 0 0)
			(layers "F.Cu" "F.Mask" "F.Paste")
			(net "JTAG_P0_R_TRST_N")
		)
		(pad "2" smd circle
			(at 0.40005 0 270)
			(size 0 0)
			(layers "F.Cu" "F.Mask" "F.Paste")
			(net "JTAG_CPU0_TRST_N")
		)
	)
)
